(kicad_pcb
	(version 20260206)
	(generator "pcbnew")
	(generator_version "10.0")
	(general
		(thickness 1.6)
		(legacy_teardrops no)
	)
	(paper "A4")
	(title_block
		(title "panther-plus-userver — 13130-1b_20150205.brd")
		(comment 1 "Honey Badger (Wiwynn) / footprints 1290-1296 of 1509")
	)
	(layers
		(0 "F.Cu" signal "TOP")
		(4 "In1.Cu" signal "L2")
		(6 "In2.Cu" signal "L3")
		(8 "In3.Cu" signal "L4")
		(10 "In4.Cu" signal "L5")
		(12 "In5.Cu" signal "L6")
		(14 "In6.Cu" signal "L7")
		(16 "In7.Cu" signal "L8")
		(18 "In8.Cu" signal "L9")
		(20 "In9.Cu" signal "L10")
		(22 "In10.Cu" signal "L11")
		(2 "B.Cu" signal "BOTTOM")
		(9 "F.Adhes" user "F.Adhesive")
		(11 "B.Adhes" user "B.Adhesive")
		(13 "F.Paste" user "Package Geometry/Pastemask Top")
		(15 "B.Paste" user "Package Geometry/Pastemask Bottom")
		(5 "F.SilkS" user "Ref Des/Silkscreen Top")
		(7 "B.SilkS" user "Ref Des/Silkscreen Bottom")
		(1 "F.Mask" user "Board Geometry/Soldermask Top")
		(3 "B.Mask" user "Board Geometry/Soldermask Bottom")
		(17 "Dwgs.User" user "User.Drawings")
		(19 "Cmts.User" user "User.Comments")
		(21 "Eco1.User" user "User.Eco1")
		(23 "Eco2.User" user "User.Eco2")
		(25 "Edge.Cuts" user "Board Geometry/Outline")
		(27 "Margin" user)
		(31 "F.CrtYd" user "Package Geometry/Place Bound Top")
		(29 "B.CrtYd" user "Package Geometry/Place Bound Bottom")
		(35 "F.Fab" user "Ref Des/Assembly Top")
		(33 "B.Fab" user "Ref Des/Assembly Bottom")
	)
	(footprint ""
		(layer "B.Cu")
		(at 26.2255 -12.7)
		(property "Reference" "C272"
			(at 0 0 0)
			(layer "B.SilkS")
			(hide yes)
			(effects
				(font
					(size 1.27 1.27)
				)
				(justify mirror)
			)
		)
		(property "Value" "SCD1U16V2KX-3GP"
			(at -1.1811 -2.7051 0)
			(unlocked yes)
			(layer "B.Fab")
			(hide yes)
			(effects
				(font
					(size 1.016 1.016)
					(thickness 0.1524)
				)
				(justify mirror)
			)
		)
		(property "Device Type" "C402H22"
			(at -1.1811 -4.2291 0)
			(unlocked yes)
			(layer "B.Fab")
			(hide yes)
			(effects
				(font
					(size 1.016 1.016)
					(thickness 0.1524)
				)
				(justify mirror)
			)
		)
		(duplicate_pad_numbers_are_jumpers no)
		(fp_rect
			(start 0.381 0.7366)
			(end -0.381 -0.7366)
			(stroke
				(width 0)
				(type default)
			)
			(fill no)
			(layer "B.CrtYd")
		)
		(fp_rect
			(start 0.381 0.7366)
			(end -0.381 -0.7366)
			(stroke
				(width 0)
				(type default)
			)
			(fill no)
			(layer "B.Fab")
		)
		(pad "1" smd custom
			(at 0 -0.4572 180)
			(size 0.1143 0.1143)
			(layers "B.Cu" "B.Mask" "B.Paste")
			(net "P2E_CPU_ETH10G_C_TX_DP9")
			(options
				(clearance outline)
				(anchor circle)
			)
			(primitives
				(gr_poly
					(pts
						(arc
							(start -0.254 0.1778)
							(mid -0.239121 0.213721)
							(end -0.2032 0.2286)
						)
						(arc
							(start 0.2032 0.2286)
							(mid 0.239121 0.213721)
							(end 0.254 0.1778)
						)
						(arc
							(start 0.254 -0.1778)
							(mid 0.239121 -0.213721)
							(end 0.2032 -0.2286)
						)
						(arc
							(start -0.2032 -0.2286)
							(mid -0.239121 -0.213721)
							(end -0.254 -0.1778)
						)
					)
					(width 0)
					(fill yes)
				)
			)
		)
		(pad "2" smd custom
			(at 0 0.4572 180)
			(size 0.1143 0.1143)
			(layers "B.Cu" "B.Mask" "B.Paste")
			(net "P2E_CPU_ETH10G_TX_DP9")
			(options
				(clearance outline)
				(anchor circle)
			)
			(primitives
				(gr_poly
					(pts
						(arc
							(start -0.254 0.1778)
							(mid -0.239121 0.213721)
							(end -0.2032 0.2286)
						)
						(arc
							(start 0.2032 0.2286)
							(mid 0.239121 0.213721)
							(end 0.254 0.1778)
						)
						(arc
							(start 0.254 -0.1778)
							(mid 0.239121 -0.213721)
							(end 0.2032 -0.2286)
						)
						(arc
							(start -0.2032 -0.2286)
							(mid -0.239121 -0.213721)
							(end -0.254 -0.1778)
						)
					)
					(width 0)
					(fill yes)
				)
			)
		)
	)
	(footprint ""
		(layer "B.Cu")
		(at 51.181 -17.018)
		(property "Reference" "C201"
			(at 0 0 0)
			(layer "B.SilkS")
			(hide yes)
			(effects
				(font
					(size 1.27 1.27)
				)
				(justify mirror)
			)
		)
		(property "Value" "SCD1U10V2KX-5GP"
			(at -1.1811 -2.7051 0)
			(unlocked yes)
			(layer "B.Fab")
			(hide yes)
			(effects
				(font
					(size 1.016 1.016)
					(thickness 0.1524)
				)
				(justify mirror)
			)
		)
		(property "Device Type" "C402H22"
			(at -1.1811 -4.2291 0)
			(unlocked yes)
			(layer "B.Fab")
			(hide yes)
			(effects
				(font
					(size 1.016 1.016)
					(thickness 0.1524)
				)
				(justify mirror)
			)
		)
		(duplicate_pad_numbers_are_jumpers no)
		(fp_rect
			(start 0.381 0.7366)
			(end -0.381 -0.7366)
			(stroke
				(width 0)
				(type default)
			)
			(fill no)
			(layer "B.CrtYd")
		)
		(fp_rect
			(start 0.381 0.7366)
			(end -0.381 -0.7366)
			(stroke
				(width 0)
				(type default)
			)
			(fill no)
			(layer "B.Fab")
		)
		(pad "1" smd custom
			(at 0 -0.4572 180)
			(size 0.1143 0.1143)
			(layers "B.Cu" "B.Mask" "B.Paste")
			(net "P3V3_VDDA_CLKBUFF")
			(options
				(clearance outline)
				(anchor circle)
			)
			(primitives
				(gr_poly
					(pts
						(arc
							(start -0.254 0.1778)
							(mid -0.239121 0.213721)
							(end -0.2032 0.2286)
						)
						(arc
							(start 0.2032 0.2286)
							(mid 0.239121 0.213721)
							(end 0.254 0.1778)
						)
						(arc
							(start 0.254 -0.1778)
							(mid 0.239121 -0.213721)
							(end 0.2032 -0.2286)
						)
						(arc
							(start -0.2032 -0.2286)
							(mid -0.239121 -0.213721)
							(end -0.254 -0.1778)
						)
					)
					(width 0)
					(fill yes)
				)
			)
		)
		(pad "2" smd custom
			(at 0 0.4572 180)
			(size 0.1143 0.1143)
			(layers "B.Cu" "B.Mask" "B.Paste")
			(net "GND")
			(options
				(clearance outline)
				(anchor circle)
			)
			(primitives
				(gr_poly
					(pts
						(arc
							(start -0.254 0.1778)
							(mid -0.239121 0.213721)
							(end -0.2032 0.2286)
						)
						(arc
							(start 0.2032 0.2286)
							(mid 0.239121 0.213721)
							(end 0.254 0.1778)
						)
						(arc
							(start 0.254 -0.1778)
							(mid 0.239121 -0.213721)
							(end 0.2032 -0.2286)
						)
						(arc
							(start -0.2032 -0.2286)
							(mid -0.239121 -0.213721)
							(end -0.254 -0.1778)
						)
					)
					(width 0)
					(fill yes)
				)
			)
		)
	)
	(footprint ""
		(layer "B.Cu")
		(at 58.2168 -13.335 180)
		(property "Reference" "U31"
			(at 0 0 0)
			(layer "B.SilkS")
			(hide yes)
			(effects
				(font
					(size 1.27 1.27)
				)
				(justify mirror)
			)
		)
		(property "Value" "SN74LVC1G07DCKRG4-2-GP"
			(at 0 -8.0772 180)
			(unlocked yes)
			(layer "B.Fab")
			(hide yes)
			(effects
				(font
					(size 1.016 1.016)
					(thickness 0.1524)
				)
				(justify mirror)
			)
		)
		(property "Device Type" "SC70-5H44"
			(at 0 -9.6012 180)
			(unlocked yes)
			(layer "B.Fab")
			(hide yes)
			(effects
				(font
					(size 1.016 1.016)
					(thickness 0.1524)
				)
				(justify mirror)
			)
		)
		(duplicate_pad_numbers_are_jumpers no)
		(fp_line
			(start 1.0033 0.3302)
			(end 1.0033 -0.3302)
			(stroke
				(width 0.1524)
				(type default)
			)
			(layer "B.SilkS")
		)
		(fp_line
			(start 1.0033 -0.3302)
			(end -1.0033 -0.3302)
			(stroke
				(width 0.1524)
				(type default)
			)
			(layer "B.SilkS")
		)
		(fp_line
			(start -1.0033 0.3302)
			(end 1.0033 0.3302)
			(stroke
				(width 0.1524)
				(type default)
			)
			(layer "B.SilkS")
		)
		(fp_line
			(start -1.0033 -0.3302)
			(end -1.0033 0.3302)
			(stroke
				(width 0.1524)
				(type default)
			)
			(layer "B.SilkS")
		)
		(fp_poly
			(pts
				(xy 1.0033 1.4859) (xy 1.0033 0.8001) (xy 1.1811 0.8001) (xy 1.1811 -0.8001) (xy 1.0033 -0.8001)
				(xy 1.0033 -1.4859) (xy -1.0033 -1.4859) (xy -1.0033 -0.8001) (xy -1.1811 -0.8001) (xy -1.1811 0.8001)
				(xy -1.0033 0.8001) (xy -1.0033 1.4859) (xy -0.2921 1.4859) (xy -0.2921 0.8001) (xy 0.2921 0.8001)
				(xy 0.2921 1.4859)
			)
			(stroke
				(width 0)
				(type default)
			)
			(fill no)
			(layer "B.CrtYd")
		)
		(fp_poly
			(pts
				(xy 1.0033 1.4859) (xy 1.0033 0.8001) (xy 1.1811 0.8001) (xy 1.1811 -0.8001) (xy 1.0033 -0.8001)
				(xy 1.0033 -1.4859) (xy -1.0033 -1.4859) (xy -1.0033 -0.8001) (xy -1.1811 -0.8001) (xy -1.1811 0.8001)
				(xy -1.0033 0.8001) (xy -1.0033 1.4859) (xy -0.2921 1.4859) (xy -0.2921 0.8001) (xy 0.2921 0.8001)
				(xy 0.2921 1.4859)
			)
			(stroke
				(width 0)
				(type default)
			)
			(fill no)
			(layer "B.Fab")
		)
		(pad "1" smd rect
			(at -0.65024 -0.93472)
			(size 0.3556 0.762)
			(layers "B.Cu" "B.Mask" "B.Paste")
			(net "Net_144")
		)
		(pad "2" smd rect
			(at 0 -0.93472)
			(size 0.3556 0.762)
			(layers "B.Cu" "B.Mask" "B.Paste")
			(net "PMU_PLTRST#")
		)
		(pad "3" smd rect
			(at 0.65024 -0.93472)
			(size 0.3556 0.762)
			(layers "B.Cu" "B.Mask" "B.Paste")
			(net "GND")
		)
		(pad "4" smd rect
			(at 0.65024 0.93472)
			(size 0.3556 0.762)
			(layers "B.Cu" "B.Mask" "B.Paste")
			(net "PMU_BUF_PLTRST#")
		)
		(pad "5" smd rect
			(at -0.65024 0.93472)
			(size 0.3556 0.762)
			(layers "B.Cu" "B.Mask" "B.Paste")
			(net "P3V3_STBY")
		)
	)
	(footprint ""
		(layer "B.Cu")
		(at 88.773 -44.069 180)
		(property "Reference" "R299"
			(at 0 0 0)
			(layer "B.SilkS")
			(hide yes)
			(effects
				(font
					(size 1.27 1.27)
				)
				(justify mirror)
			)
		)
		(property "Value" "45D3R2F-L-GP"
			(at -0.064008 -3.993896 180)
			(unlocked yes)
			(layer "B.Fab")
			(hide yes)
			(effects
				(font
					(size 1.016 1.016)
					(thickness 0.1524)
				)
				(justify mirror)
			)
		)
		(property "Device Type" "R402H16"
			(at -0.064008 -5.517896 180)
			(unlocked yes)
			(layer "B.Fab")
			(hide yes)
			(effects
				(font
					(size 1.016 1.016)
					(thickness 0.1524)
				)
				(justify mirror)
			)
		)
		(duplicate_pad_numbers_are_jumpers no)
		(fp_rect
			(start 0.381 0.8382)
			(end -0.381 -0.8382)
			(stroke
				(width 0)
				(type default)
			)
			(fill no)
			(layer "B.CrtYd")
		)
		(fp_rect
			(start 0.381 0.8382)
			(end -0.381 -0.8382)
			(stroke
				(width 0)
				(type default)
			)
			(fill no)
			(layer "B.Fab")
		)
		(pad "1" smd custom
			(at 0 -0.4318)
			(size 0.127 0.127)
			(layers "B.Cu" "B.Mask" "B.Paste")
			(net "PD_USB_RCOMP")
			(options
				(clearance outline)
				(anchor circle)
			)
			(primitives
				(gr_poly
					(pts
						(arc
							(start -0.2032 0.2794)
							(mid -0.239121 0.264521)
							(end -0.254 0.2286)
						)
						(arc
							(start -0.254 -0.2286)
							(mid -0.239121 -0.264521)
							(end -0.2032 -0.2794)
						)
						(arc
							(start 0.2032 -0.2794)
							(mid 0.239121 -0.264521)
							(end 0.254 -0.2286)
						)
						(arc
							(start 0.254 0.2286)
							(mid 0.239121 0.264521)
							(end 0.2032 0.2794)
						)
					)
					(width 0)
					(fill yes)
				)
			)
		)
		(pad "2" smd custom
			(at 0 0.4318)
			(size 0.127 0.127)
			(layers "B.Cu" "B.Mask" "B.Paste")
			(net "GND")
			(options
				(clearance outline)
				(anchor circle)
			)
			(primitives
				(gr_poly
					(pts
						(arc
							(start -0.2032 0.2794)
							(mid -0.239121 0.264521)
							(end -0.254 0.2286)
						)
						(arc
							(start -0.254 -0.2286)
							(mid -0.239121 -0.264521)
							(end -0.2032 -0.2794)
						)
						(arc
							(start 0.2032 -0.2794)
							(mid 0.239121 -0.264521)
							(end 0.254 -0.2286)
						)
						(arc
							(start 0.254 0.2286)
							(mid 0.239121 0.264521)
							(end 0.2032 0.2794)
						)
					)
					(width 0)
					(fill yes)
				)
			)
		)
	)
	(footprint ""
		(layer "B.Cu")
		(at 18.796 -24.765 -90)
		(property "Reference" "PR87"
			(at 0 0 90)
			(layer "B.SilkS")
			(hide yes)
			(effects
				(font
					(size 1.27 1.27)
				)
				(justify mirror)
			)
		)
		(property "Value" "0R2J-2-GP"
			(at -1.7907 -1.1176 270)
			(unlocked yes)
			(layer "B.Fab")
			(hide yes)
			(effects
				(font
					(size 1.016 1.016)
					(thickness 0.1524)
				)
				(justify mirror)
			)
		)
		(property "Device Type" "R402H16"
			(at -1.7907 -2.6416 270)
			(unlocked yes)
			(layer "B.Fab")
			(hide yes)
			(effects
				(font
					(size 1.016 1.016)
					(thickness 0.1524)
				)
				(justify mirror)
			)
		)
		(duplicate_pad_numbers_are_jumpers no)
		(fp_rect
			(start 0.381 0.8382)
			(end -0.381 -0.8382)
			(stroke
				(width 0)
				(type default)
			)
			(fill no)
			(layer "B.CrtYd")
		)
		(fp_rect
			(start 0.381 0.8382)
			(end -0.381 -0.8382)
			(stroke
				(width 0)
				(type default)
			)
			(fill no)
			(layer "B.Fab")
		)
		(pad "1" smd custom
			(at 0 -0.4318 90)
			(size 0.127 0.127)
			(layers "B.Cu" "B.Mask" "B.Paste")
			(net "P1V0")
			(options
				(clearance outline)
				(anchor circle)
			)
			(primitives
				(gr_poly
					(pts
						(arc
							(start -0.2032 0.2794)
							(mid -0.239121 0.264521)
							(end -0.254 0.2286)
						)
						(arc
							(start -0.254 -0.2286)
							(mid -0.239121 -0.264521)
							(end -0.2032 -0.2794)
						)
						(arc
							(start 0.2032 -0.2794)
							(mid 0.239121 -0.264521)
							(end 0.254 -0.2286)
						)
						(arc
							(start 0.254 0.2286)
							(mid 0.239121 0.264521)
							(end 0.2032 0.2794)
						)
					)
					(width 0)
					(fill yes)
				)
			)
		)
		(pad "2" smd custom
			(at 0 0.4318 90)
			(size 0.127 0.127)
			(layers "B.Cu" "B.Mask" "B.Paste")
			(net "P1V0_ROVP")
			(options
				(clearance outline)
				(anchor circle)
			)
			(primitives
				(gr_poly
					(pts
						(arc
							(start -0.2032 0.2794)
							(mid -0.239121 0.264521)
							(end -0.254 0.2286)
						)
						(arc
							(start -0.254 -0.2286)
							(mid -0.239121 -0.264521)
							(end -0.2032 -0.2794)
						)
						(arc
							(start 0.2032 -0.2794)
							(mid 0.239121 -0.264521)
							(end 0.254 -0.2286)
						)
						(arc
							(start 0.254 0.2286)
							(mid 0.239121 0.264521)
							(end 0.2032 0.2794)
						)
					)
					(width 0)
					(fill yes)
				)
			)
		)
	)
	(footprint ""
		(layer "B.Cu")
		(at 80.137 -65.786)
		(property "Reference" "R293"
			(at 0 0 0)
			(layer "B.SilkS")
			(hide yes)
			(effects
				(font
					(size 1.27 1.27)
				)
				(justify mirror)
			)
		)
		(property "Value" "56D2R2F-GP"
			(at -0.064008 -3.993896 0)
			(unlocked yes)
			(layer "B.Fab")
			(hide yes)
			(effects
				(font
					(size 1.016 1.016)
					(thickness 0.1524)
				)
				(justify mirror)
			)
		)
		(property "Device Type" "R402H16"
			(at -0.064008 -5.517896 0)
			(unlocked yes)
			(layer "B.Fab")
			(hide yes)
			(effects
				(font
					(size 1.016 1.016)
					(thickness 0.1524)
				)
				(justify mirror)
			)
		)
		(duplicate_pad_numbers_are_jumpers no)
		(fp_rect
			(start 0.381 0.8382)
			(end -0.381 -0.8382)
			(stroke
				(width 0)
				(type default)
			)
			(fill no)
			(layer "B.CrtYd")
		)
		(fp_rect
			(start 0.381 0.8382)
			(end -0.381 -0.8382)
			(stroke
				(width 0)
				(type default)
			)
			(fill no)
			(layer "B.Fab")
		)
		(pad "1" smd custom
			(at 0 -0.4318 180)
			(size 0.127 0.127)
			(layers "B.Cu" "B.Mask" "B.Paste")
			(net "P1V0")
			(options
				(clearance outline)
				(anchor circle)
			)
			(primitives
				(gr_poly
					(pts
						(arc
							(start -0.2032 0.2794)
							(mid -0.239121 0.264521)
							(end -0.254 0.2286)
						)
						(arc
							(start -0.254 -0.2286)
							(mid -0.239121 -0.264521)
							(end -0.2032 -0.2794)
						)
						(arc
							(start 0.2032 -0.2794)
							(mid 0.239121 -0.264521)
							(end 0.254 -0.2286)
						)
						(arc
							(start 0.254 0.2286)
							(mid 0.239121 0.264521)
							(end 0.2032 0.2794)
						)
					)
					(width 0)
					(fill yes)
				)
			)
		)
		(pad "2" smd custom
			(at 0 0.4318 180)
			(size 0.127 0.127)
			(layers "B.Cu" "B.Mask" "B.Paste")
			(net "SVID_CPU_ALERT#")
			(options
				(clearance outline)
				(anchor circle)
			)
			(primitives
				(gr_poly
					(pts
						(arc
							(start -0.2032 0.2794)
							(mid -0.239121 0.264521)
							(end -0.254 0.2286)
						)
						(arc
							(start -0.254 -0.2286)
							(mid -0.239121 -0.264521)
							(end -0.2032 -0.2794)
						)
						(arc
							(start 0.2032 -0.2794)
							(mid 0.239121 -0.264521)
							(end 0.254 -0.2286)
						)
						(arc
							(start 0.254 0.2286)
							(mid 0.239121 0.264521)
							(end 0.2032 0.2794)
						)
					)
					(width 0)
					(fill yes)
				)
			)
		)
	)
	(footprint ""
		(layer "B.Cu")
		(at 136.779 -60.198 180)
		(property "Reference" "R232"
			(at 0 0 0)
			(layer "B.SilkS")
			(hide yes)
			(effects
				(font
					(size 1.27 1.27)
				)
				(justify mirror)
			)
		)
		(property "Value" "4K7R2F-GP"
			(at -0.064008 -3.993896 180)
			(unlocked yes)
			(layer "B.Fab")
			(hide yes)
			(effects
				(font
					(size 1.016 1.016)
					(thickness 0.1524)
				)
				(justify mirror)
			)
		)
		(property "Device Type" "R402H16"
			(at -0.064008 -5.517896 180)
			(unlocked yes)
			(layer "B.Fab")
			(hide yes)
			(effects
				(font
					(size 1.016 1.016)
					(thickness 0.1524)
				)
				(justify mirror)
			)
		)
		(duplicate_pad_numbers_are_jumpers no)
		(fp_rect
			(start 0.381 0.8382)
			(end -0.381 -0.8382)
			(stroke
				(width 0)
				(type default)
			)
			(fill no)
			(layer "B.CrtYd")
		)
		(fp_rect
			(start 0.381 0.8382)
			(end -0.381 -0.8382)
			(stroke
				(width 0)
				(type default)
			)
			(fill no)
			(layer "B.Fab")
		)
		(pad "1" smd custom
			(at 0 -0.4318)
			(size 0.127 0.127)
			(layers "B.Cu" "B.Mask" "B.Paste")
			(net "CHA_0_SA0")
			(options
				(clearance outline)
				(anchor circle)
			)
			(primitives
				(gr_poly
					(pts
						(arc
							(start -0.2032 0.2794)
							(mid -0.239121 0.264521)
							(end -0.254 0.2286)
						)
						(arc
							(start -0.254 -0.2286)
							(mid -0.239121 -0.264521)
							(end -0.2032 -0.2794)
						)
						(arc
							(start 0.2032 -0.2794)
							(mid 0.239121 -0.264521)
							(end 0.254 -0.2286)
						)
						(arc
							(start 0.254 0.2286)
							(mid 0.239121 0.264521)
							(end 0.2032 0.2794)
						)
					)
					(width 0)
					(fill yes)
				)
			)
		)
		(pad "2" smd custom
			(at 0 0.4318)
			(size 0.127 0.127)
			(layers "B.Cu" "B.Mask" "B.Paste")
			(net "GND")
			(options
				(clearance outline)
				(anchor circle)
			)
			(primitives
				(gr_poly
					(pts
						(arc
							(start -0.2032 0.2794)
							(mid -0.239121 0.264521)
							(end -0.254 0.2286)
						)
						(arc
							(start -0.254 -0.2286)
							(mid -0.239121 -0.264521)
							(end -0.2032 -0.2794)
						)
						(arc
							(start 0.2032 -0.2794)
							(mid 0.239121 -0.264521)
							(end 0.254 -0.2286)
						)
						(arc
							(start 0.254 0.2286)
							(mid 0.239121 0.264521)
							(end 0.2032 0.2794)
						)
					)
					(width 0)
					(fill yes)
				)
			)
		)
	)
)
